(kicad_pcb
	(version 20241229)
	(generator "pcbnew")
	(generator_version "9.0")
	(general
		(thickness 1.294)
		(legacy_teardrops no)
	)
	(paper "A3")
	(title_block
		(title "Kintex 410T devboard")
		(date "2024-04-03")
		(rev "1.1.2")
		(comment 9 "footprints 585-590 of 975")
	)
	(layers
		(0 "F.Cu" mixed)
		(4 "In1.Cu" power)
		(6 "In2.Cu" power)
		(8 "In3.Cu" mixed)
		(10 "In4.Cu" power)
		(12 "In5.Cu" mixed)
		(14 "In6.Cu" power)
		(16 "In7.Cu" mixed)
		(18 "In8.Cu" power)
		(2 "B.Cu" mixed)
		(9 "F.Adhes" user "F.Adhesive")
		(11 "B.Adhes" user "B.Adhesive")
		(13 "F.Paste" user)
		(15 "B.Paste" user)
		(5 "F.SilkS" user "F.Silkscreen")
		(7 "B.SilkS" user "B.Silkscreen")
		(1 "F.Mask" user)
		(3 "B.Mask" user)
		(17 "Dwgs.User" user "User.Drawings")
		(19 "Cmts.User" user "User.Comments")
		(21 "Eco1.User" user "User.Eco1")
		(23 "Eco2.User" user "User.Eco2")
		(25 "Edge.Cuts" user)
		(27 "Margin" user)
		(31 "F.CrtYd" user "F.Courtyard")
		(29 "B.CrtYd" user "B.Courtyard")
		(35 "F.Fab" user)
		(33 "B.Fab" user)
	)
	(footprint "antmicro-footprints:C_0603_1608Metric"
		(layer "B.Cu")
		(at 216.1 126.2 -90)
		(descr "Capacitor SMD 0603")
		(tags "capacitor 0603")
		(property "Reference" "C3"
			(at -0.8 -1.375 90)
			(layer "B.SilkS")
			(effects
				(font
					(size 0.7 0.7)
					(thickness 0.15)
				)
				(justify left bottom mirror)
			)
		)
		(property "Value" "C_47u_0603"
			(at 0 -1.6 90)
			(layer "B.Fab")
			(effects
				(font
					(size 0.7 0.7)
					(thickness 0.15)
				)
				(justify left bottom mirror)
			)
		)
		(property "Description" "SMD Multilayer Ceramic Capacitor, 47 µF, 6.3 V, 0603 [1608 Metric], ± 20%, X5R, GRM Series"
			(at 0 0 270)
			(layer "F.Fab")
			(hide yes)
			(effects
				(font
					(size 1.27 1.27)
					(thickness 0.15)
				)
			)
		)
		(property "Author" "Antmicro"
			(at 89.9 342.3 0)
			(layer "B.Fab")
			(hide yes)
			(effects
				(font
					(size 1 1)
					(thickness 0.15)
				)
				(justify mirror)
			)
		)
		(property "Dielectric" ""
			(at 89.9 342.3 0)
			(layer "B.Fab")
			(hide yes)
			(effects
				(font
					(size 1 1)
					(thickness 0.15)
				)
				(justify mirror)
			)
		)
		(property "License" "Apache-2.0"
			(at 89.9 342.3 0)
			(layer "B.Fab")
			(hide yes)
			(effects
				(font
					(size 1 1)
					(thickness 0.15)
				)
				(justify mirror)
			)
		)
		(property "MPN" "GRM188R60J476ME15D"
			(at 89.9 342.3 0)
			(layer "B.Fab")
			(hide yes)
			(effects
				(font
					(size 1 1)
					(thickness 0.15)
				)
				(justify mirror)
			)
		)
		(property "Manufacturer" "Murata"
			(at 89.9 342.3 0)
			(layer "B.Fab")
			(hide yes)
			(effects
				(font
					(size 1 1)
					(thickness 0.15)
				)
				(justify mirror)
			)
		)
		(property "Val" "47u"
			(at 89.9 342.3 0)
			(layer "B.Fab")
			(hide yes)
			(effects
				(font
					(size 1 1)
					(thickness 0.15)
				)
				(justify mirror)
			)
		)
		(property "Voltage" ""
			(at 89.9 342.3 0)
			(layer "B.Fab")
			(hide yes)
			(effects
				(font
					(size 1 1)
					(thickness 0.15)
				)
				(justify mirror)
			)
		)
		(sheetname "FPGA Bank 12 & 13")
		(sheetfile "fpga-bank-12-13.kicad_sch")
		(attr smd)
		(fp_line
			(start -0.15 0.4)
			(end 0.15 0.4)
			(stroke
				(width 0.15)
				(type solid)
			)
			(layer "B.SilkS")
		)
		(fp_line
			(start -0.15 -0.4)
			(end 0.15 -0.4)
			(stroke
				(width 0.15)
				(type solid)
			)
			(layer "B.SilkS")
		)
		(fp_rect
			(start -1.25 0.65)
			(end 1.25 -0.65)
			(stroke
				(width 0.05)
				(type solid)
			)
			(fill no)
			(layer "B.CrtYd")
		)
		(fp_rect
			(start -0.8 0.4)
			(end 0.8 -0.4)
			(stroke
				(width 0.15)
				(type solid)
			)
			(fill no)
			(layer "B.Fab")
		)
		(pad "1" smd roundrect
			(at -0.7 0 270)
			(size 0.8 1)
			(layers "B.Cu" "B.Mask" "B.Paste")
			(roundrect_rratio 0.2)
			(net 1 "GND")
			(pintype "passive")
		)
		(pad "2" smd roundrect
			(at 0.7 0 270)
			(size 0.8 1)
			(layers "B.Cu" "B.Mask" "B.Paste")
			(roundrect_rratio 0.2)
			(net 24 "+3V3")
			(pintype "passive")
		)
	)
	(footprint "antmicro-footprints:R_0402_1005Metric"
		(layer "B.Cu")
		(at 223.2 146.2 -90)
		(descr "Resistor SMD 0402")
		(tags "resistor SMD 0402")
		(property "Reference" "R236"
			(at -3.625 -0.375 90)
			(layer "B.SilkS")
			(effects
				(font
					(size 0.7 0.7)
					(thickness 0.15)
				)
				(justify left bottom mirror)
			)
		)
		(property "Value" "R_10R_0402"
			(at 0 -1.4 90)
			(layer "B.Fab")
			(effects
				(font
					(size 0.7 0.7)
					(thickness 0.15)
				)
				(justify left bottom mirror)
			)
		)
		(property "Description" "SMD Chip Resistor, 10 ohm, ± 1%, 62.5 mW, 0402 [1005 Metric], Thick Film, General Purpose"
			(at 0 0 270)
			(layer "F.Fab")
			(hide yes)
			(effects
				(font
					(size 1.27 1.27)
					(thickness 0.15)
				)
			)
		)
		(property "Author" "Antmicro"
			(at 77 369.4 0)
			(layer "B.Fab")
			(hide yes)
			(effects
				(font
					(size 1 1)
					(thickness 0.15)
				)
				(justify mirror)
			)
		)
		(property "License" "Apache-2.0"
			(at 77 369.4 0)
			(layer "B.Fab")
			(hide yes)
			(effects
				(font
					(size 1 1)
					(thickness 0.15)
				)
				(justify mirror)
			)
		)
		(property "MPN" "CR0402-FX-10R0GLF"
			(at 77 369.4 0)
			(layer "B.Fab")
			(hide yes)
			(effects
				(font
					(size 1 1)
					(thickness 0.15)
				)
				(justify mirror)
			)
		)
		(property "Manufacturer" "Bourns"
			(at 77 369.4 0)
			(layer "B.Fab")
			(hide yes)
			(effects
				(font
					(size 1 1)
					(thickness 0.15)
				)
				(justify mirror)
			)
		)
		(property "Tolerance" "1%"
			(at 77 369.4 0)
			(layer "B.Fab")
			(hide yes)
			(effects
				(font
					(size 1 1)
					(thickness 0.15)
				)
				(justify mirror)
			)
		)
		(property "Val" "10R"
			(at 77 369.4 0)
			(layer "B.Fab")
			(hide yes)
			(effects
				(font
					(size 1 1)
					(thickness 0.15)
				)
				(justify mirror)
			)
		)
		(sheetname "HDMI + Ethernet")
		(sheetfile "hdmi-ethernet.kicad_sch")
		(attr smd)
		(fp_rect
			(start -0.925 0.47)
			(end 0.925 -0.47)
			(stroke
				(width 0.05)
				(type default)
			)
			(fill no)
			(layer "B.CrtYd")
		)
		(fp_rect
			(start -0.5 0.25)
			(end 0.5 -0.25)
			(stroke
				(width 0.15)
				(type solid)
			)
			(fill no)
			(layer "B.Fab")
		)
		(pad "1" smd roundrect
			(at -0.48 0 270)
			(size 0.59 0.64)
			(layers "B.Cu" "B.Mask" "B.Paste")
			(roundrect_rratio 0.25)
			(net 519 "/FPGA Bank 18 & 32/ETH_RMII.RXD0")
			(pintype "passive")
		)
		(pad "2" smd roundrect
			(at 0.48 0 270)
			(size 0.59 0.64)
			(layers "B.Cu" "B.Mask" "B.Paste")
			(roundrect_rratio 0.25)
			(net 946 "/HDMI + Ethernet/ETH_PHY_RXDO")
			(pintype "passive")
		)
	)
	(footprint "antmicro-footprints:R_0402_1005Metric"
		(layer "B.Cu")
		(at 241.499999 84.699999 90)
		(descr "Resistor SMD 0402")
		(tags "resistor SMD 0402")
		(property "Reference" "R126"
			(at -0.725001 0.400001 270)
			(layer "B.SilkS")
			(effects
				(font
					(size 0.7 0.7)
					(thickness 0.15)
				)
				(justify left bottom mirror)
			)
		)
		(property "Value" "R_100R_0402"
			(at 0 -1.4 270)
			(layer "B.Fab")
			(effects
				(font
					(size 0.7 0.7)
					(thickness 0.15)
				)
				(justify left bottom mirror)
			)
		)
		(property "Description" "SMD Chip Resistor, 100 ohm, ± 1%, 62.5 mW, 0402 [1005 Metric], Thick Film, General Purpose"
			(at 0 0 90)
			(layer "F.Fab")
			(hide yes)
			(effects
				(font
					(size 1.27 1.27)
					(thickness 0.15)
				)
			)
		)
		(property "Author" "Antmicro"
			(at 326.199998 -156.8 0)
			(layer "B.Fab")
			(hide yes)
			(effects
				(font
					(size 1 1)
					(thickness 0.15)
				)
				(justify mirror)
			)
		)
		(property "License" "Apache-2.0"
			(at 326.199998 -156.8 0)
			(layer "B.Fab")
			(hide yes)
			(effects
				(font
					(size 1 1)
					(thickness 0.15)
				)
				(justify mirror)
			)
		)
		(property "MPN" "CR0402-FX-1000GLF"
			(at 326.199998 -156.8 0)
			(layer "B.Fab")
			(hide yes)
			(effects
				(font
					(size 1 1)
					(thickness 0.15)
				)
				(justify mirror)
			)
		)
		(property "Manufacturer" "Bourns"
			(at 326.199998 -156.8 0)
			(layer "B.Fab")
			(hide yes)
			(effects
				(font
					(size 1 1)
					(thickness 0.15)
				)
				(justify mirror)
			)
		)
		(property "Tolerance" "1%"
			(at 326.199998 -156.8 0)
			(layer "B.Fab")
			(hide yes)
			(effects
				(font
					(size 1 1)
					(thickness 0.15)
				)
				(justify mirror)
			)
		)
		(property "Val" "100R"
			(at 326.199998 -156.8 0)
			(layer "B.Fab")
			(hide yes)
			(effects
				(font
					(size 1 1)
					(thickness 0.15)
				)
				(justify mirror)
			)
		)
		(sheetname "User GPIO + LED + button + DIP switch")
		(sheetfile "user-gpio.kicad_sch")
		(attr smd)
		(fp_rect
			(start -0.925 0.47)
			(end 0.925 -0.47)
			(stroke
				(width 0.05)
				(type default)
			)
			(fill no)
			(layer "B.CrtYd")
		)
		(fp_rect
			(start -0.5 0.25)
			(end 0.5 -0.25)
			(stroke
				(width 0.15)
				(type solid)
			)
			(fill no)
			(layer "B.Fab")
		)
		(pad "1" smd roundrect
			(at -0.48 0 90)
			(size 0.59 0.64)
			(layers "B.Cu" "B.Mask" "B.Paste")
			(roundrect_rratio 0.25)
			(net 471 "/FPGA Bank 12 & 13/PMOD_B.IO3")
			(pintype "passive")
		)
		(pad "2" smd roundrect
			(at 0.48 0 90)
			(size 0.59 0.64)
			(layers "B.Cu" "B.Mask" "B.Paste")
			(roundrect_rratio 0.25)
			(net 813 "/User GPIO + LED + button + DIP switch/PMOD_B_3")
			(pintype "passive")
		)
	)
	(footprint "antmicro-footprints:R_0402_1005Metric"
		(layer "B.Cu")
		(at 190.6 84.8 90)
		(descr "Resistor SMD 0402")
		(tags "resistor SMD 0402")
		(property "Reference" "R137"
			(at -0.725 0.4 270)
			(layer "B.SilkS")
			(effects
				(font
					(size 0.7 0.7)
					(thickness 0.15)
				)
				(justify left bottom mirror)
			)
		)
		(property "Value" "R_100R_0402"
			(at 0 -1.4 270)
			(layer "B.Fab")
			(effects
				(font
					(size 0.7 0.7)
					(thickness 0.15)
				)
				(justify left bottom mirror)
			)
		)
		(property "Description" "SMD Chip Resistor, 100 ohm, ± 1%, 62.5 mW, 0402 [1005 Metric], Thick Film, General Purpose"
			(at 0 0 90)
			(layer "F.Fab")
			(hide yes)
			(effects
				(font
					(size 1.27 1.27)
					(thickness 0.15)
				)
			)
		)
		(property "Author" "Antmicro"
			(at 275.4 -105.8 0)
			(layer "B.Fab")
			(hide yes)
			(effects
				(font
					(size 1 1)
					(thickness 0.15)
				)
				(justify mirror)
			)
		)
		(property "License" "Apache-2.0"
			(at 275.4 -105.8 0)
			(layer "B.Fab")
			(hide yes)
			(effects
				(font
					(size 1 1)
					(thickness 0.15)
				)
				(justify mirror)
			)
		)
		(property "MPN" "CR0402-FX-1000GLF"
			(at 275.4 -105.8 0)
			(layer "B.Fab")
			(hide yes)
			(effects
				(font
					(size 1 1)
					(thickness 0.15)
				)
				(justify mirror)
			)
		)
		(property "Manufacturer" "Bourns"
			(at 275.4 -105.8 0)
			(layer "B.Fab")
			(hide yes)
			(effects
				(font
					(size 1 1)
					(thickness 0.15)
				)
				(justify mirror)
			)
		)
		(property "Tolerance" "1%"
			(at 275.4 -105.8 0)
			(layer "B.Fab")
			(hide yes)
			(effects
				(font
					(size 1 1)
					(thickness 0.15)
				)
				(justify mirror)
			)
		)
		(property "Val" "100R"
			(at 275.4 -105.8 0)
			(layer "B.Fab")
			(hide yes)
			(effects
				(font
					(size 1 1)
					(thickness 0.15)
				)
				(justify mirror)
			)
		)
		(sheetname "User GPIO + LED + button + DIP switch")
		(sheetfile "user-gpio.kicad_sch")
		(attr smd)
		(fp_rect
			(start -0.925 0.47)
			(end 0.925 -0.47)
			(stroke
				(width 0.05)
				(type default)
			)
			(fill no)
			(layer "B.CrtYd")
		)
		(fp_rect
			(start -0.5 0.25)
			(end 0.5 -0.25)
			(stroke
				(width 0.15)
				(type solid)
			)
			(fill no)
			(layer "B.Fab")
		)
		(pad "1" smd roundrect
			(at -0.48 0 90)
			(size 0.59 0.64)
			(layers "B.Cu" "B.Mask" "B.Paste")
			(roundrect_rratio 0.25)
			(net 828 "/User GPIO + LED + button + DIP switch/CW_20PIN_TSCK")
			(pintype "passive")
		)
		(pad "2" smd roundrect
			(at 0.48 0 90)
			(size 0.59 0.64)
			(layers "B.Cu" "B.Mask" "B.Paste")
			(roundrect_rratio 0.25)
			(net 477 "/FPGA Bank 12 & 13/CW_HEADER.TSCK")
			(pintype "passive")
		)
	)
	(footprint "antmicro-footprints:C_0603_1608Metric"
		(layer "B.Cu")
		(at 186 181.85)
		(descr "Capacitor SMD 0603")
		(tags "capacitor 0603")
		(property "Reference" "C314"
			(at 1.3 -0.575 180)
			(layer "B.SilkS")
			(effects
				(font
					(size 0.7 0.7)
					(thickness 0.15)
				)
				(justify left bottom mirror)
			)
		)
		(property "Value" "C_1u_25V_0603"
			(at 0 -1.6 180)
			(layer "B.Fab")
			(effects
				(font
					(size 0.7 0.7)
					(thickness 0.15)
				)
				(justify left bottom mirror)
			)
		)
		(property "Description" "SMD Multilayer Ceramic Capacitor, 1 µF, 25 V, 0603 [1608 Metric], ± 10%, X5R, CL"
			(at 0 0 0)
			(layer "F.Fab")
			(hide yes)
			(effects
				(font
					(size 1.27 1.27)
					(thickness 0.15)
				)
			)
		)
		(property "Author" "Antmicro"
			(at 0 0 0)
			(layer "B.Fab")
			(hide yes)
			(effects
				(font
					(size 1 1)
					(thickness 0.15)
				)
				(justify mirror)
			)
		)
		(property "Dielectric" ""
			(at 0 0 0)
			(layer "B.Fab")
			(hide yes)
			(effects
				(font
					(size 1 1)
					(thickness 0.15)
				)
				(justify mirror)
			)
		)
		(property "License" "Apache-2.0"
			(at 0 0 0)
			(layer "B.Fab")
			(hide yes)
			(effects
				(font
					(size 1 1)
					(thickness 0.15)
				)
				(justify mirror)
			)
		)
		(property "MPN" "CL10A105KA8NNNC"
			(at 0 0 0)
			(layer "B.Fab")
			(hide yes)
			(effects
				(font
					(size 1 1)
					(thickness 0.15)
				)
				(justify mirror)
			)
		)
		(property "Manufacturer" "Samsung Electro-Mechanics"
			(at 0 0 0)
			(layer "B.Fab")
			(hide yes)
			(effects
				(font
					(size 1 1)
					(thickness 0.15)
				)
				(justify mirror)
			)
		)
		(property "Val" "1u"
			(at 0 0 0)
			(layer "B.Fab")
			(hide yes)
			(effects
				(font
					(size 1 1)
					(thickness 0.15)
				)
				(justify mirror)
			)
		)
		(property "Voltage" "25V"
			(at 0 0 0)
			(layer "B.Fab")
			(hide yes)
			(effects
				(font
					(size 1 1)
					(thickness 0.15)
				)
				(justify mirror)
			)
		)
		(sheetname "DC-DC Converters")
		(sheetfile "dc-dc.kicad_sch")
		(attr smd)
		(fp_line
			(start -0.15 -0.4)
			(end 0.15 -0.4)
			(stroke
				(width 0.15)
				(type solid)
			)
			(layer "B.SilkS")
		)
		(fp_line
			(start -0.15 0.4)
			(end 0.15 0.4)
			(stroke
				(width 0.15)
				(type solid)
			)
			(layer "B.SilkS")
		)
		(fp_rect
			(start -1.25 0.65)
			(end 1.25 -0.65)
			(stroke
				(width 0.05)
				(type solid)
			)
			(fill no)
			(layer "B.CrtYd")
		)
		(fp_rect
			(start -0.8 0.4)
			(end 0.8 -0.4)
			(stroke
				(width 0.15)
				(type solid)
			)
			(fill no)
			(layer "B.Fab")
		)
		(pad "1" smd roundrect
			(at -0.7 0)
			(size 0.8 1)
			(layers "B.Cu" "B.Mask" "B.Paste")
			(roundrect_rratio 0.2)
			(net 702 "VDC")
			(pintype "passive")
		)
		(pad "2" smd roundrect
			(at 0.7 0)
			(size 0.8 1)
			(layers "B.Cu" "B.Mask" "B.Paste")
			(roundrect_rratio 0.2)
			(net 1 "GND")
			(pintype "passive")
		)
	)
	(footprint "antmicro-footprints:C_0201"
		(layer "B.Cu")
		(at 190 131.5 180)
		(descr "Capacitor SMD 0201")
		(tags "capacitor SMD 0201")
		(property "Reference" "C157"
			(at 0.55 -0.4 0)
			(layer "B.SilkS")
			(effects
				(font
					(size 0.7 0.7)
					(thickness 0.15)
				)
				(justify left bottom mirror)
			)
		)
		(property "Value" "C_100n_0201"
			(at 0 -1.4 0)
			(layer "B.Fab")
			(effects
				(font
					(size 0.7 0.7)
					(thickness 0.15)
				)
				(justify left bottom mirror)
			)
		)
		(property "Description" "SMD Multilayer Ceramic Capacitor, 0.1 µF, 6.3 V, 0201 [0603 Metric], ± 10%, X6S, CC Series"
			(at 0 0 180)
			(layer "F.Fab")
			(hide yes)
			(effects
				(font
					(size 1.27 1.27)
					(thickness 0.15)
				)
			)
		)
		(property "Author" "Antmicro"
			(at 380 263 0)
			(layer "B.Fab")
			(hide yes)
			(effects
				(font
					(size 1 1)
					(thickness 0.15)
				)
				(justify mirror)
			)
		)
		(property "Dielectric" ""
			(at 380 263 0)
			(layer "B.Fab")
			(hide yes)
			(effects
				(font
					(size 1 1)
					(thickness 0.15)
				)
				(justify mirror)
			)
		)
		(property "License" "Apache-2.0"
			(at 380 263 0)
			(layer "B.Fab")
			(hide yes)
			(effects
				(font
					(size 1 1)
					(thickness 0.15)
				)
				(justify mirror)
			)
		)
		(property "MPN" "CC0201KRX6S5BB104"
			(at 380 263 0)
			(layer "B.Fab")
			(hide yes)
			(effects
				(font
					(size 1 1)
					(thickness 0.15)
				)
				(justify mirror)
			)
		)
		(property "Manufacturer" "YAGEO"
			(at 380 263 0)
			(layer "B.Fab")
			(hide yes)
			(effects
				(font
					(size 1 1)
					(thickness 0.15)
				)
				(justify mirror)
			)
		)
		(property "Val" "100n"
			(at 380 263 0)
			(layer "B.Fab")
			(hide yes)
			(effects
				(font
					(size 1 1)
					(thickness 0.15)
				)
				(justify mirror)
			)
		)
		(property "Voltage" ""
			(at 380 263 0)
			(layer "B.Fab")
			(hide yes)
			(effects
				(font
					(size 1 1)
					(thickness 0.15)
				)
				(justify mirror)
			)
		)
		(sheetname "FPGA supply")
		(sheetfile "fpga-supply.kicad_sch")
		(attr smd)
		(fp_rect
			(start -0.7 0.35)
			(end 0.7 -0.35)
			(stroke
				(width 0.05)
				(type default)
			)
			(fill no)
			(layer "B.CrtYd")
		)
		(fp_rect
			(start 0.3 -0.15)
			(end -0.301 0.149)
			(stroke
				(width 0.15)
				(type solid)
			)
			(fill no)
			(layer "B.Fab")
		)
		(pad "" smd roundrect
			(at -0.349 0.002 180)
			(size 0.318 0.36)
			(layers "B.Paste")
			(roundrect_rratio 0.25)
		)
		(pad "" smd roundrect
			(at 0.341 0.002 180)
			(size 0.318 0.36)
			(layers "B.Paste")
			(roundrect_rratio 0.25)
		)
		(pad "1" smd roundrect
			(at -0.321 0.002 180)
			(size 0.46 0.4)
			(layers "B.Cu" "B.Mask")
			(roundrect_rratio 0.25)
			(net 1 "GND")
			(pintype "passive")
		)
		(pad "2" smd roundrect
			(at 0.32 0.002 180)
			(size 0.46 0.4)
			(layers "B.Cu" "B.Mask")
			(roundrect_rratio 0.25)
			(net 8 "+1V2_MGTAVTT")
			(pintype "passive")
		)
	)
)
